(kicad_pcb
	(version 20260206)
	(generator "pcbnew")
	(generator_version "10.0")
	(general
		(thickness 1.6)
		(legacy_teardrops no)
	)
	(paper "A4")
	(title_block
		(title "Bryce Canyon_F.DPB_16315-1-OCP.brd")
		(comment 1 "Bryce Canyon / footprints 1673-1680 of 2223")
	)
	(layers
		(0 "F.Cu" signal "TOP")
		(4 "In1.Cu" signal "L2GND")
		(6 "In2.Cu" signal "L3")
		(8 "In3.Cu" signal "L4GND")
		(10 "In4.Cu" signal "L5")
		(12 "In5.Cu" signal "L6VCC")
		(14 "In6.Cu" signal "L7VCC")
		(16 "In7.Cu" signal "L8")
		(18 "In8.Cu" signal "L9GND")
		(20 "In9.Cu" signal "L10")
		(22 "In10.Cu" signal "L11GND")
		(2 "B.Cu" signal "BOTTOM")
		(9 "F.Adhes" user "F.Adhesive")
		(11 "B.Adhes" user "B.Adhesive")
		(13 "F.Paste" user "Package Geometry/Pastemask Top")
		(15 "B.Paste" user "Package Geometry/Pastemask Bottom")
		(5 "F.SilkS" user "Ref Des/Silkscreen Top")
		(7 "B.SilkS" user "Ref Des/Silkscreen Bottom")
		(1 "F.Mask" user "Board Geometry/Soldermask Top")
		(3 "B.Mask" user "Board Geometry/Soldermask Bottom")
		(17 "Dwgs.User" user "User.Drawings")
		(19 "Cmts.User" user "User.Comments")
		(21 "Eco1.User" user "User.Eco1")
		(23 "Eco2.User" user "User.Eco2")
		(25 "Edge.Cuts" user "Board Geometry/Outline")
		(27 "Margin" user)
		(31 "F.CrtYd" user "Package Geometry/Place Bound Top")
		(29 "B.CrtYd" user "Package Geometry/Place Bound Bottom")
		(35 "F.Fab" user "Ref Des/Assembly Top")
		(33 "B.Fab" user "Ref Des/Assembly Bottom")
	)
	(footprint ""
		(layer "F.Cu")
		(at 444.6397 -65.039494 -90)
		(property "Reference" "R916"
			(at 0 0 270)
			(layer "F.SilkS")
			(hide yes)
			(effects
				(font
					(size 1.27 1.27)
				)
			)
		)
		(property "Value" "220R3F-1-GP"
			(at -0.0254 -2.5146 270)
			(unlocked yes)
			(layer "F.Fab")
			(hide yes)
			(effects
				(font
					(size 1.016 1.016)
					(thickness 0.1524)
				)
			)
		)
		(property "Device Type" "R603H22"
			(at -0.0254 -4.0386 270)
			(unlocked yes)
			(layer "F.Fab")
			(hide yes)
			(effects
				(font
					(size 1.016 1.016)
					(thickness 0.1524)
				)
			)
		)
		(duplicate_pad_numbers_are_jumpers no)
		(fp_line
			(start -0.4826 0)
			(end -0.2032 0)
			(stroke
				(width 0.2032)
				(type default)
			)
			(layer "F.SilkS")
		)
		(fp_line
			(start 0.2032 0)
			(end 0.4826 0)
			(stroke
				(width 0.2032)
				(type default)
			)
			(layer "F.SilkS")
		)
		(fp_rect
			(start -0.5842 1.3335)
			(end 0.5842 -1.3335)
			(stroke
				(width 0)
				(type default)
			)
			(fill no)
			(layer "F.CrtYd")
		)
		(fp_rect
			(start -0.5842 1.3335)
			(end 0.5842 -1.3335)
			(stroke
				(width 0)
				(type default)
			)
			(fill no)
			(layer "F.Fab")
		)
		(pad "1" smd custom
			(at 0 -0.762 270)
			(size 0.2159 0.2159)
			(layers "F.Cu" "F.Mask" "F.Paste")
			(net "HDD_PRSNT_34")
			(options
				(clearance outline)
				(anchor circle)
			)
			(primitives
				(gr_poly
					(pts
						(arc
							(start -0.3302 -0.4318)
							(mid -0.402042 -0.402042)
							(end -0.4318 -0.3302)
						)
						(arc
							(start -0.4318 0.3302)
							(mid -0.402042 0.402042)
							(end -0.3302 0.4318)
						)
						(arc
							(start 0.3302 0.4318)
							(mid 0.402042 0.402042)
							(end 0.4318 0.3302)
						)
						(arc
							(start 0.4318 -0.3302)
							(mid 0.402042 -0.402042)
							(end 0.3302 -0.4318)
						)
					)
					(width 0)
					(fill yes)
				)
			)
		)
		(pad "2" smd custom
			(at 0 0.762 270)
			(size 0.2159 0.2159)
			(layers "F.Cu" "F.Mask" "F.Paste")
			(net "DRIVE_A_34_INS")
			(options
				(clearance outline)
				(anchor circle)
			)
			(primitives
				(gr_poly
					(pts
						(arc
							(start -0.3302 -0.4318)
							(mid -0.402042 -0.402042)
							(end -0.4318 -0.3302)
						)
						(arc
							(start -0.4318 0.3302)
							(mid -0.402042 0.402042)
							(end -0.3302 0.4318)
						)
						(arc
							(start 0.3302 0.4318)
							(mid 0.402042 0.402042)
							(end 0.4318 0.3302)
						)
						(arc
							(start 0.4318 -0.3302)
							(mid 0.402042 -0.402042)
							(end 0.3302 -0.4318)
						)
					)
					(width 0)
					(fill yes)
				)
			)
		)
	)
	(footprint ""
		(layer "F.Cu")
		(at 412.912052 -176.127918 -90)
		(property "Reference" "C315"
			(at 0 0 270)
			(layer "F.SilkS")
			(hide yes)
			(effects
				(font
					(size 1.27 1.27)
				)
			)
		)
		(property "Value" "SCD01U50V2KX-1GP"
			(at 1.1811 -2.7051 270)
			(unlocked yes)
			(layer "F.Fab")
			(hide yes)
			(effects
				(font
					(size 1.016 1.016)
					(thickness 0.1524)
				)
			)
		)
		(property "Device Type" "C402H22"
			(at 1.1811 -4.2291 270)
			(unlocked yes)
			(layer "F.Fab")
			(hide yes)
			(effects
				(font
					(size 1.016 1.016)
					(thickness 0.1524)
				)
			)
		)
		(duplicate_pad_numbers_are_jumpers no)
		(fp_rect
			(start -0.4318 0.9525)
			(end 0.4318 -0.9525)
			(stroke
				(width 0)
				(type default)
			)
			(fill no)
			(layer "F.CrtYd")
		)
		(fp_rect
			(start -0.4318 0.9525)
			(end 0.4318 -0.9525)
			(stroke
				(width 0)
				(type default)
			)
			(fill no)
			(layer "F.Fab")
		)
		(pad "1" smd custom
			(at 0 -0.4445 270)
			(size 0.1524 0.1524)
			(layers "F.Cu" "F.Mask" "F.Paste")
			(net "HDD_PRSNT_21")
			(options
				(clearance outline)
				(anchor circle)
			)
			(primitives
				(gr_poly
					(pts
						(arc
							(start 0.3048 -0.2032)
							(mid 0.275042 -0.275042)
							(end 0.2032 -0.3048)
						)
						(arc
							(start -0.2032 -0.3048)
							(mid -0.275042 -0.275042)
							(end -0.3048 -0.2032)
						)
						(arc
							(start -0.3048 0.2032)
							(mid -0.275042 0.275042)
							(end -0.2032 0.3048)
						)
						(arc
							(start 0.2032 0.3048)
							(mid 0.275042 0.275042)
							(end 0.3048 0.2032)
						)
					)
					(width 0)
					(fill yes)
				)
			)
		)
		(pad "2" smd custom
			(at 0 0.4445 270)
			(size 0.1524 0.1524)
			(layers "F.Cu" "F.Mask" "F.Paste")
			(net "GND")
			(options
				(clearance outline)
				(anchor circle)
			)
			(primitives
				(gr_poly
					(pts
						(arc
							(start 0.3048 -0.2032)
							(mid 0.275042 -0.275042)
							(end 0.2032 -0.3048)
						)
						(arc
							(start -0.2032 -0.3048)
							(mid -0.275042 -0.275042)
							(end -0.3048 -0.2032)
						)
						(arc
							(start -0.3048 0.2032)
							(mid -0.275042 0.275042)
							(end -0.2032 0.3048)
						)
						(arc
							(start 0.2032 0.3048)
							(mid 0.275042 0.275042)
							(end 0.3048 0.2032)
						)
					)
					(width 0)
					(fill yes)
				)
			)
		)
	)
	(footprint ""
		(layer "F.Cu")
		(at 416.284664 -274.219416 -90)
		(property "Reference" "C155"
			(at 0 0 270)
			(layer "F.SilkS")
			(hide yes)
			(effects
				(font
					(size 1.27 1.27)
				)
			)
		)
		(property "Value" "SCD01U16V1KX-GP"
			(at -2.8321 -1.7399 270)
			(unlocked yes)
			(layer "F.Fab")
			(hide yes)
			(effects
				(font
					(size 1.016 1.016)
					(thickness 0.1524)
				)
			)
		)
		(property "Device Type" "C0201H13"
			(at -2.8321 -3.2639 270)
			(unlocked yes)
			(layer "F.Fab")
			(hide yes)
			(effects
				(font
					(size 1.016 1.016)
					(thickness 0.1524)
				)
			)
		)
		(duplicate_pad_numbers_are_jumpers no)
		(fp_rect
			(start -0.2794 0.6477)
			(end 0.2794 -0.6477)
			(stroke
				(width 0)
				(type default)
			)
			(fill no)
			(layer "F.CrtYd")
		)
		(fp_rect
			(start -0.2794 0.6477)
			(end 0.2794 -0.6477)
			(stroke
				(width 0)
				(type default)
			)
			(fill no)
			(layer "F.Fab")
		)
		(pad "1" smd custom
			(at 0 -0.2794 270)
			(size 0.0762 0.0762)
			(layers "F.Cu" "F.Mask" "F.Paste")
			(net "SAS_HDD_RX_N9")
			(options
				(clearance outline)
				(anchor circle)
			)
			(primitives
				(gr_poly
					(pts
						(arc
							(start 0.1524 -0.127)
							(mid 0.137521 -0.162921)
							(end 0.1016 -0.1778)
						)
						(arc
							(start -0.1016 -0.1778)
							(mid -0.137521 -0.162921)
							(end -0.1524 -0.127)
						)
						(arc
							(start -0.1524 0.127)
							(mid -0.137521 0.162921)
							(end -0.1016 0.1778)
						)
						(arc
							(start 0.1016 0.1778)
							(mid 0.137521 0.162921)
							(end 0.1524 0.127)
						)
					)
					(width 0)
					(fill yes)
				)
			)
		)
		(pad "2" smd custom
			(at 0 0.2794 270)
			(size 0.0762 0.0762)
			(layers "F.Cu" "F.Mask" "F.Paste")
			(net "PHY_SCC_A_TO_DRV_A_9_DN")
			(options
				(clearance outline)
				(anchor circle)
			)
			(primitives
				(gr_poly
					(pts
						(arc
							(start 0.1524 -0.127)
							(mid 0.137521 -0.162921)
							(end 0.1016 -0.1778)
						)
						(arc
							(start -0.1016 -0.1778)
							(mid -0.137521 -0.162921)
							(end -0.1524 -0.127)
						)
						(arc
							(start -0.1524 0.127)
							(mid -0.137521 0.162921)
							(end -0.1016 0.1778)
						)
						(arc
							(start 0.1016 0.1778)
							(mid 0.137521 0.162921)
							(end 0.1524 0.127)
						)
					)
					(width 0)
					(fill yes)
				)
			)
		)
	)
	(footprint ""
		(layer "F.Cu")
		(at 481.24999 -5.500116)
		(property "Reference" ""
			(at 0 0 0)
			(layer "F.SilkS")
			(hide yes)
			(effects
				(font
					(size 1.27 1.27)
				)
			)
		)
		(property "Value" "*"
			(at -4.729734 -0.095504 0)
			(unlocked yes)
			(layer "F.Fab")
			(hide yes)
			(effects
				(font
					(size 1.016 1.016)
					(thickness 0.1524)
				)
			)
		)
		(duplicate_pad_numbers_are_jumpers no)
		(fp_poly
			(pts
				(arc
					(start 4.064 0)
					(mid -4.064 0)
					(end 4.064 0)
				)
			)
			(stroke
				(width 0)
				(type default)
			)
			(fill no)
			(layer "B.CrtYd")
		)
		(fp_poly
			(pts
				(arc
					(start 4.064 0)
					(mid -4.064 0)
					(end 4.064 0)
				)
			)
			(stroke
				(width 0)
				(type default)
			)
			(fill no)
			(layer "F.CrtYd")
		)
		(fp_poly
			(pts
				(arc
					(start 4.064 0)
					(mid -4.064 0)
					(end 4.064 0)
				)
			)
			(stroke
				(width 0)
				(type default)
			)
			(fill no)
			(layer "B.Fab")
		)
		(fp_poly
			(pts
				(arc
					(start 4.064 0)
					(mid -4.064 0)
					(end 4.064 0)
				)
			)
			(stroke
				(width 0)
				(type default)
			)
			(fill no)
			(layer "F.Fab")
		)
		(pad "1" thru_hole circle
			(at 0 0)
			(size 7.5184 7.5184)
			(drill 4.2164)
			(layers "*.Cu" "*.Mask")
			(remove_unused_layers no)
			(net "Net_61")
			(clearance -1.143)
			(thermal_gap 0.3048)
			(padstack
				(mode front_inner_back)
				(layer "Inner"
					(shape circle)
					(size 4.6228 4.6228)
					(clearance 0.3048)
				)
				(layer "B.Cu"
					(shape circle)
					(size 7.5184 7.5184)
					(clearance -1.143)
				)
			)
		)
	)
	(footprint ""
		(layer "F.Cu")
		(at 394.56995 -73.954894 180)
		(property "Reference" "C461"
			(at 0 0 180)
			(layer "F.SilkS")
			(hide yes)
			(effects
				(font
					(size 1.27 1.27)
				)
			)
		)
		(property "Value" "SC4D7U25V5KX-1-GP"
			(at -0.0762 -6.1214 180)
			(unlocked yes)
			(layer "F.Fab")
			(hide yes)
			(effects
				(font
					(size 1.016 1.016)
					(thickness 0.1524)
				)
			)
		)
		(property "Device Type" "C805H58"
			(at -0.0762 -8.1534 180)
			(unlocked yes)
			(layer "F.Fab")
			(hide yes)
			(effects
				(font
					(size 1.016 1.016)
					(thickness 0.1524)
				)
			)
		)
		(duplicate_pad_numbers_are_jumpers no)
		(fp_line
			(start 0.635 0)
			(end -0.635 0)
			(stroke
				(width 0.508)
				(type default)
			)
			(layer "F.SilkS")
		)
		(fp_rect
			(start -0.9652 1.778)
			(end 0.9652 -1.778)
			(stroke
				(width 0)
				(type default)
			)
			(fill no)
			(layer "F.CrtYd")
		)
		(fp_poly
			(pts
				(xy -0.9652 -1.778) (xy 0.9652 -1.778) (xy 0.9652 1.778) (xy -0.9652 1.778)
			)
			(stroke
				(width 0)
				(type default)
			)
			(fill no)
			(layer "F.Fab")
		)
		(pad "1" smd rect
			(at 0 -0.9652 180)
			(size 1.397 1.143)
			(layers "F.Cu" "F.Mask" "F.Paste")
			(net "P12V_HDD32")
		)
		(pad "2" smd rect
			(at 0 0.9652 180)
			(size 1.397 1.143)
			(layers "F.Cu" "F.Mask" "F.Paste")
			(net "GND")
		)
	)
	(footprint ""
		(layer "F.Cu")
		(at 190.8302 -68.707)
		(property "Reference" "TP147"
			(at 0 0 0)
			(layer "F.SilkS")
			(hide yes)
			(effects
				(font
					(size 1.27 1.27)
				)
			)
		)
		(property "Value" "TPAD32-GP"
			(at -0.0508 -1.6764 0)
			(unlocked yes)
			(layer "F.Fab")
			(hide yes)
			(effects
				(font
					(size 1.016 1.016)
					(thickness 0.1524)
				)
			)
		)
		(property "Device Type" "TPAD32"
			(at -0.0508 -3.2004 0)
			(unlocked yes)
			(layer "F.Fab")
			(hide yes)
			(effects
				(font
					(size 1.016 1.016)
					(thickness 0.1524)
				)
			)
		)
		(duplicate_pad_numbers_are_jumpers no)
		(fp_poly
			(pts
				(arc
					(start 0.4064 0)
					(mid -0.4064 0)
					(end 0.4064 0)
				)
			)
			(stroke
				(width 0)
				(type default)
			)
			(fill no)
			(layer "F.CrtYd")
		)
		(fp_poly
			(pts
				(arc
					(start 0.7112 0)
					(mid -0.7112 0)
					(end 0.7112 0)
				)
			)
			(stroke
				(width 0)
				(type default)
			)
			(fill no)
			(layer "F.Fab")
		)
		(pad "1" smd circle
			(at 0 0)
			(size 0.8128 0.8128)
			(layers "F.Cu" "F.Mask" "F.Paste")
			(net "ACT_HDD_29")
		)
	)
	(footprint ""
		(layer "F.Cu")
		(at 320.990468 -242.210844)
		(property "Reference" "R241"
			(at 0 0 0)
			(layer "F.SilkS")
			(hide yes)
			(effects
				(font
					(size 1.27 1.27)
				)
			)
		)
		(property "Value" "130R3F-GP"
			(at -0.0254 -2.5146 0)
			(unlocked yes)
			(layer "F.Fab")
			(hide yes)
			(effects
				(font
					(size 1.016 1.016)
					(thickness 0.1524)
				)
			)
		)
		(property "Device Type" "R603H22"
			(at -0.0254 -4.0386 0)
			(unlocked yes)
			(layer "F.Fab")
			(hide yes)
			(effects
				(font
					(size 1.016 1.016)
					(thickness 0.1524)
				)
			)
		)
		(duplicate_pad_numbers_are_jumpers no)
		(fp_line
			(start -0.4826 0)
			(end -0.2032 0)
			(stroke
				(width 0.2032)
				(type default)
			)
			(layer "F.SilkS")
		)
		(fp_line
			(start 0.2032 0)
			(end 0.4826 0)
			(stroke
				(width 0.2032)
				(type default)
			)
			(layer "F.SilkS")
		)
		(fp_rect
			(start -0.5842 1.3335)
			(end 0.5842 -1.3335)
			(stroke
				(width 0)
				(type default)
			)
			(fill no)
			(layer "F.CrtYd")
		)
		(fp_rect
			(start -0.5842 1.3335)
			(end 0.5842 -1.3335)
			(stroke
				(width 0)
				(type default)
			)
			(fill no)
			(layer "F.Fab")
		)
		(pad "1" smd custom
			(at 0 -0.762)
			(size 0.2159 0.2159)
			(layers "F.Cu" "F.Mask" "F.Paste")
			(net "P5V_A_3")
			(options
				(clearance outline)
				(anchor circle)
			)
			(primitives
				(gr_poly
					(pts
						(arc
							(start -0.3302 -0.4318)
							(mid -0.402042 -0.402042)
							(end -0.4318 -0.3302)
						)
						(arc
							(start -0.4318 0.3302)
							(mid -0.402042 0.402042)
							(end -0.3302 0.4318)
						)
						(arc
							(start 0.3302 0.4318)
							(mid 0.402042 0.402042)
							(end 0.4318 0.3302)
						)
						(arc
							(start 0.4318 -0.3302)
							(mid 0.402042 -0.402042)
							(end 0.3302 -0.4318)
						)
					)
					(width 0)
					(fill yes)
				)
			)
		)
		(pad "2" smd custom
			(at 0 0.762)
			(size 0.2159 0.2159)
			(layers "F.Cu" "F.Mask" "F.Paste")
			(net "FLT_HDD6")
			(options
				(clearance outline)
				(anchor circle)
			)
			(primitives
				(gr_poly
					(pts
						(arc
							(start -0.3302 -0.4318)
							(mid -0.402042 -0.402042)
							(end -0.4318 -0.3302)
						)
						(arc
							(start -0.4318 0.3302)
							(mid -0.402042 0.402042)
							(end -0.3302 0.4318)
						)
						(arc
							(start 0.3302 0.4318)
							(mid 0.402042 0.402042)
							(end 0.4318 0.3302)
						)
						(arc
							(start 0.4318 -0.3302)
							(mid 0.402042 -0.402042)
							(end 0.3302 -0.4318)
						)
					)
					(width 0)
					(fill yes)
				)
			)
		)
	)
	(footprint ""
		(layer "F.Cu")
		(at 346.700094 -324.39991)
		(property "Reference" "RLED32"
			(at 0 0 0)
			(layer "F.SilkS")
			(hide yes)
			(effects
				(font
					(size 1.27 1.27)
				)
			)
		)
		(property "Value" "LED-BY-19-GP"
			(at -2.132076 1.414018 0)
			(unlocked yes)
			(layer "F.Fab")
			(hide yes)
			(effects
				(font
					(size 1.016 1.016)
					(thickness 0.1524)
				)
			)
		)
		(property "Device Type" "LED-1615-4PH26"
			(at -2.132076 -0.109982 0)
			(unlocked yes)
			(layer "F.Fab")
			(hide yes)
			(effects
				(font
					(size 1.016 1.016)
					(thickness 0.1524)
				)
			)
		)
		(duplicate_pad_numbers_are_jumpers no)
		(fp_line
			(start -1.2954 0.254)
			(end -1.2954 1.6002)
			(stroke
				(width 0.508)
				(type default)
			)
			(layer "F.SilkS")
		)
		(fp_line
			(start -1.2954 1.6002)
			(end 1.2954 1.6002)
			(stroke
				(width 0.508)
				(type default)
			)
			(layer "F.SilkS")
		)
		(fp_line
			(start -1.1176 -1.4224)
			(end 1.1176 -1.4224)
			(stroke
				(width 0.1524)
				(type default)
			)
			(layer "F.SilkS")
		)
		(fp_line
			(start -1.1176 1.4224)
			(end -1.1176 -1.4224)
			(stroke
				(width 0.1524)
				(type default)
			)
			(layer "F.SilkS")
		)
		(fp_line
			(start 1.1176 -1.4224)
			(end 1.1176 1.4224)
			(stroke
				(width 0.1524)
				(type default)
			)
			(layer "F.SilkS")
		)
		(fp_line
			(start 1.1176 1.4224)
			(end -1.1176 1.4224)
			(stroke
				(width 0.1524)
				(type default)
			)
			(layer "F.SilkS")
		)
		(fp_line
			(start 1.2954 1.6002)
			(end 1.2954 0.254)
			(stroke
				(width 0.508)
				(type default)
			)
			(layer "F.SilkS")
		)
		(fp_rect
			(start -0.7493 0.8001)
			(end 0.7493 -0.8001)
			(stroke
				(width 0)
				(type default)
			)
			(fill no)
			(layer "F.CrtYd")
		)
		(fp_poly
			(pts
				(xy -1.3716 1.6764) (xy -1.3716 -1.6764) (xy 1.3716 -1.6764) (xy 1.3716 0.0635) (xy 0.7493 0.0635)
				(xy 0.7493 -0.8001) (xy -0.7493 -0.8001) (xy -0.7493 0.8001) (xy 0.7493 0.8001) (xy 0.7493 0.0762)
				(xy 1.3716 0.0762) (xy 1.3716 1.6764)
			)
			(stroke
				(width 0)
				(type default)
			)
			(fill no)
			(layer "F.CrtYd")
		)
		(fp_rect
			(start -1.3716 1.6764)
			(end 1.3716 -1.6764)
			(stroke
				(width 0)
				(type default)
			)
			(fill no)
			(layer "F.Fab")
		)
		(pad "1" smd rect
			(at 0.50038 -0.73025)
			(size 0.7112 0.8636)
			(layers "F.Cu" "F.Mask" "F.Paste")
			(net "DRV_ACT_31")
		)
		(pad "2" smd rect
			(at -0.50038 -0.73025)
			(size 0.7112 0.8636)
			(layers "F.Cu" "F.Mask" "F.Paste")
			(net "FLT_HDD31")
		)
		(pad "3" smd rect
			(at 0.50038 0.73025)
			(size 0.7112 0.8636)
			(layers "F.Cu" "F.Mask" "F.Paste")
			(net "DRV_ACT_31_N")
		)
		(pad "4" smd rect
			(at -0.50038 0.73025)
			(size 0.7112 0.8636)
			(layers "F.Cu" "F.Mask" "F.Paste")
			(net "FLT_HDD31_N")
		)
	)
)
